# T6G (Grand Teton) — schematic netlist excerpt (pin names and nets, part order shuffled) for the footprints in the layout excerpt that follows; sources: Cadence DE-HDL packaged netlist, KiCad conversion of 04192023_DAF0TMB3IC0_F0TG_MB_C_brd_V02_OCP.brd

U12  M24M02DRMN6TP  M24M02-DRMN6TP IC  pkg SOIC8XH  page 322
  DU1  = NC
  DU2  = NC
  E2  = U12_E2
  VSS  = GND
  SDA  = SMB_RT_CPU1_P0_ROM_SDA
  SCL  = SMB_RT_CPU1_P0_ROM_SCL
  WC_N  = GND
  VCC  = P1V8_CPU1_RT_1D

R1476  Q_RES  4.7K 5% EMPTY  pkg 0201LF  page 298 : A = P1V8_CPU0_RT_1D ; B = JTAG_TDI_RT_CPU0_P2
PC118_3  Q_CAP  1UF 25V 10% X6S  pkg C0402  page 202 : A = SW_P12V_AUX_PVDDCR_CPU1_P0_FLT ; B = GND

(kicad_pcb
	(version 20260206)
	(generator "pcbnew")
	(generator_version "10.0")
	(general
		(thickness 1.6)
		(legacy_teardrops no)
	)
	(paper "A4")
	(title_block
		(title "04192023_DAF0TMB3IC0_F0TG_MB_C_brd_V02_OCP.brd")
		(comment 1 "Grand Teton / footprints 2665-2667 of 8354")
	)
	(layers
		(0 "F.Cu" signal "TOP")
		(4 "In1.Cu" signal "GND")
		(6 "In2.Cu" signal "IN1")
		(8 "In3.Cu" signal "GND1")
		(10 "In4.Cu" signal "IN2")
		(12 "In5.Cu" signal "GND2")
		(14 "In6.Cu" signal "IN3")
		(16 "In7.Cu" signal "GND3")
		(18 "In8.Cu" signal "VCC")
		(20 "In9.Cu" signal "VCC1")
		(22 "In10.Cu" signal "GND4")
		(24 "In11.Cu" signal "IN4")
		(26 "In12.Cu" signal "GND5")
		(28 "In13.Cu" signal "IN5")
		(30 "In14.Cu" signal "GND6")
		(32 "In15.Cu" signal "IN6")
		(34 "In16.Cu" signal "GND7")
		(2 "B.Cu" signal "BOTTOM")
		(9 "F.Adhes" user "F.Adhesive")
		(11 "B.Adhes" user "B.Adhesive")
		(13 "F.Paste" user "Package Geometry/Pastemask Top")
		(15 "B.Paste" user "Package Geometry/Pastemask Bottom")
		(5 "F.SilkS" user "Ref Des/Silkscreen Top")
		(7 "B.SilkS" user "Ref Des/Silkscreen Bottom")
		(1 "F.Mask" user "Board Geometry/Soldermask Top")
		(3 "B.Mask" user "Board Geometry/Soldermask Bottom")
		(17 "Dwgs.User" user "User.Drawings")
		(19 "Cmts.User" user "User.Comments")
		(21 "Eco1.User" user "User.Eco1")
		(23 "Eco2.User" user "User.Eco2")
		(25 "Edge.Cuts" user "Board Geometry/Outline")
		(27 "Margin" user)
		(31 "F.CrtYd" user "Package Geometry/Place Bound Top")
		(29 "B.CrtYd" user "Package Geometry/Place Bound Bottom")
		(35 "F.Fab" user "Ref Des/Assembly Top")
		(33 "B.Fab" user "Ref Des/Assembly Bottom")
	)
	(footprint ""
		(layer "F.Cu")
		(at 103.601266 -401.329906 -90)
		(property "Reference" "U12"
			(at 0.837184 -3.221482 90)
			(unlocked yes)
			(layer "F.SilkS")
			(effects
				(font
					(size 0.7874 0.5842)
					(thickness 0.1524)
				)
				(justify left)
			)
		)
		(property "Value" ""
			(at 0 0 270)
			(layer "F.Fab")
			(effects
				(font
					(size 1.27 1.27)
				)
			)
		)
		(duplicate_pad_numbers_are_jumpers no)
		(fp_line
			(start -1.8288 2.500122)
			(end 1.8288 2.500122)
			(stroke
				(width 0.1524)
				(type default)
			)
			(layer "F.SilkS")
		)
		(fp_line
			(start 1.8288 2.500122)
			(end 1.8288 -2.500122)
			(stroke
				(width 0.1524)
				(type default)
			)
			(layer "F.SilkS")
		)
		(fp_line
			(start 0 -1.4224)
			(end -1.077722 -2.500122)
			(stroke
				(width 0.1524)
				(type default)
			)
			(layer "F.SilkS")
		)
		(fp_line
			(start -1.8288 -2.500122)
			(end -1.8288 2.500122)
			(stroke
				(width 0.1524)
				(type default)
			)
			(layer "F.SilkS")
		)
		(fp_line
			(start -1.077722 -2.500122)
			(end -1.8288 -2.500122)
			(stroke
				(width 0.1524)
				(type default)
			)
			(layer "F.SilkS")
		)
		(fp_line
			(start 1.077722 -2.500122)
			(end 0 -1.4224)
			(stroke
				(width 0.1524)
				(type default)
			)
			(layer "F.SilkS")
		)
		(fp_line
			(start 1.8288 -2.500122)
			(end 1.077722 -2.500122)
			(stroke
				(width 0.1524)
				(type default)
			)
			(layer "F.SilkS")
		)
		(fp_poly
			(pts
				(xy -4.932934 -2.31648) (xy -4.932934 -1.30048) (xy -3.916934 -1.80848)
			)
			(stroke
				(width 0)
				(type default)
			)
			(fill yes)
			(layer "F.SilkS")
		)
		(fp_line
			(start -1.999996 2.500122)
			(end 1.999996 2.500122)
			(stroke
				(width 0.1)
				(type default)
			)
			(layer "F.Fab")
		)
		(fp_line
			(start 1.999996 2.500122)
			(end 1.999996 -2.500122)
			(stroke
				(width 0.1)
				(type default)
			)
			(layer "F.Fab")
		)
		(fp_line
			(start -1.999996 -2.500122)
			(end -1.999996 2.500122)
			(stroke
				(width 0.1)
				(type default)
			)
			(layer "F.Fab")
		)
		(fp_line
			(start 1.999996 -2.500122)
			(end -1.999996 -2.500122)
			(stroke
				(width 0.1)
				(type default)
			)
			(layer "F.Fab")
		)
		(fp_poly
			(pts
				(xy -4.5085 -2.413) (xy -4.5085 -1.397) (xy -3.4925 -1.905)
			)
			(stroke
				(width 0)
				(type default)
			)
			(fill yes)
			(layer "F.Fab")
		)
		(pad "1" smd rect
			(at -2.599944 -1.905 180)
			(size 0.889 1.27)
			(layers "F.Cu" "F.Mask" "F.Paste")
			(net "Net_10845")
		)
		(pad "2" smd rect
			(at -2.599944 -0.635 180)
			(size 0.889 1.27)
			(layers "F.Cu" "F.Mask" "F.Paste")
			(net "Net_10844")
		)
		(pad "3" smd rect
			(at -2.599944 0.635 180)
			(size 0.889 1.27)
			(layers "F.Cu" "F.Mask" "F.Paste")
			(net "U12_E2")
		)
		(pad "4" smd rect
			(at -2.599944 1.905 180)
			(size 0.889 1.27)
			(layers "F.Cu" "F.Mask" "F.Paste")
			(net "GND")
		)
		(pad "5" smd rect
			(at 2.599944 1.905 180)
			(size 0.889 1.27)
			(layers "F.Cu" "F.Mask" "F.Paste")
			(net "SMB_RT_CPU1_P0_ROM_SDA")
		)
		(pad "6" smd rect
			(at 2.599944 0.635 180)
			(size 0.889 1.27)
			(layers "F.Cu" "F.Mask" "F.Paste")
			(net "SMB_RT_CPU1_P0_ROM_SCL")
		)
		(pad "7" smd rect
			(at 2.599944 -0.635 180)
			(size 0.889 1.27)
			(layers "F.Cu" "F.Mask" "F.Paste")
			(net "GND")
		)
		(pad "8" smd rect
			(at 2.599944 -1.905 180)
			(size 0.889 1.27)
			(layers "F.Cu" "F.Mask" "F.Paste")
			(net "P1V8_CPU1_RT_1D")
		)
	)
	(footprint ""
		(layer "F.Cu")
		(at 321.980306 -335.09458 -90)
		(property "Reference" "PC118_3"
			(at 0 0 270)
			(layer "F.SilkS")
			(hide yes)
			(effects
				(font
					(size 1.27 1.27)
				)
			)
		)
		(property "Value" ""
			(at 0 0 270)
			(layer "F.Fab")
			(effects
				(font
					(size 1.27 1.27)
				)
			)
		)
		(duplicate_pad_numbers_are_jumpers no)
		(fp_line
			(start -0.7874 0.4064)
			(end -0.7874 -0.4064)
			(stroke
				(width 0.1524)
				(type default)
			)
			(layer "F.SilkS")
		)
		(fp_line
			(start 0.7874 0.4064)
			(end -0.7874 0.4064)
			(stroke
				(width 0.1524)
				(type default)
			)
			(layer "F.SilkS")
		)
		(fp_line
			(start -0.7874 -0.4064)
			(end 0.7874 -0.4064)
			(stroke
				(width 0.1524)
				(type default)
			)
			(layer "F.SilkS")
		)
		(fp_line
			(start 0.7874 -0.4064)
			(end 0.7874 0.4064)
			(stroke
				(width 0.1524)
				(type default)
			)
			(layer "F.SilkS")
		)
		(fp_line
			(start -0.67945 0.3048)
			(end -0.67945 -0.305054)
			(stroke
				(width 0.1)
				(type default)
			)
			(layer "F.Fab")
		)
		(fp_line
			(start -0.12065 0.3048)
			(end -0.67945 0.3048)
			(stroke
				(width 0.1)
				(type default)
			)
			(layer "F.Fab")
		)
		(fp_line
			(start 0.120396 0.3048)
			(end 0.120396 0.2794)
			(stroke
				(width 0.1)
				(type default)
			)
			(layer "F.Fab")
		)
		(fp_line
			(start 0.67945 0.3048)
			(end 0.120396 0.3048)
			(stroke
				(width 0.1)
				(type default)
			)
			(layer "F.Fab")
		)
		(fp_line
			(start -0.12065 0.2794)
			(end -0.12065 0.3048)
			(stroke
				(width 0.1)
				(type default)
			)
			(layer "F.Fab")
		)
		(fp_line
			(start 0.120396 0.2794)
			(end -0.12065 0.2794)
			(stroke
				(width 0.1)
				(type default)
			)
			(layer "F.Fab")
		)
		(fp_line
			(start -0.12065 -0.2794)
			(end 0.12065 -0.2794)
			(stroke
				(width 0.1)
				(type default)
			)
			(layer "F.Fab")
		)
		(fp_line
			(start 0.12065 -0.2794)
			(end 0.12065 -0.3048)
			(stroke
				(width 0.1)
				(type default)
			)
			(layer "F.Fab")
		)
		(fp_line
			(start 0.12065 -0.3048)
			(end 0.67945 -0.3048)
			(stroke
				(width 0.1)
				(type default)
			)
			(layer "F.Fab")
		)
		(fp_line
			(start 0.67945 -0.3048)
			(end 0.67945 0.3048)
			(stroke
				(width 0.1)
				(type default)
			)
			(layer "F.Fab")
		)
		(fp_line
			(start -0.67945 -0.305054)
			(end -0.12065 -0.305054)
			(stroke
				(width 0.1)
				(type default)
			)
			(layer "F.Fab")
		)
		(fp_line
			(start -0.12065 -0.305054)
			(end -0.12065 -0.2794)
			(stroke
				(width 0.1)
				(type default)
			)
			(layer "F.Fab")
		)
		(pad "1" smd circle
			(at -0.40005 0 270)
			(size 0 0)
			(layers "F.Cu" "F.Mask" "F.Paste")
			(net "SW_P12V_AUX_PVDDCR_CPU1_P0_FLT")
		)
		(pad "2" smd circle
			(at 0.40005 0 270)
			(size 0 0)
			(layers "F.Cu" "F.Mask" "F.Paste")
			(net "GND")
		)
	)
	(footprint ""
		(layer "F.Cu")
		(at 432.308 -407.4922)
		(property "Reference" "R1476"
			(at 0 0 0)
			(layer "F.SilkS")
			(hide yes)
			(effects
				(font
					(size 1.27 1.27)
				)
			)
		)
		(property "Value" ""
			(at 0 0 0)
			(layer "F.Fab")
			(effects
				(font
					(size 1.27 1.27)
				)
			)
		)
		(duplicate_pad_numbers_are_jumpers no)
		(fp_line
			(start -0.32512 -0.175006)
			(end 0.32512 -0.175006)
			(stroke
				(width 0.1)
				(type default)
			)
			(layer "F.Fab")
		)
		(fp_line
			(start -0.32512 0.175006)
			(end -0.32512 -0.175006)
			(stroke
				(width 0.1)
				(type default)
			)
			(layer "F.Fab")
		)
		(fp_line
			(start 0.32512 -0.175006)
			(end 0.32512 0.175006)
			(stroke
				(width 0.1)
				(type default)
			)
			(layer "F.Fab")
		)
		(fp_line
			(start 0.32512 0.175006)
			(end -0.32512 0.175006)
			(stroke
				(width 0.1)
				(type default)
			)
			(layer "F.Fab")
		)
		(pad "1" smd rect
			(at -0.2667 0)
			(size 0.3048 0.381)
			(layers "F.Cu" "F.Mask" "F.Paste")
			(net "P1V8_CPU0_RT_1D")
		)
		(pad "2" smd rect
			(at 0.2667 0 180)
			(size 0.3048 0.381)
			(layers "F.Cu" "F.Mask" "F.Paste")
			(net "JTAG_TDI_RT_CPU0_P2")
		)
	)
)
